# S9S_MB_2U (Grand Teton) — schematic netlist excerpt (pin names and nets, part order shuffled) for the footprints in the layout excerpt that follows; sources: Cadence DE-HDL packaged netlist, KiCad conversion of 03242023_DA0F0TMBIJ0_F0T_Motherboard_J_brd_V01_OCP.brd

R4799  Q_RES  100K 1% EMPTY  pkg 0402LF  page 144 : A = PRSNT_CABLE_GPU_A3_N ; B = GND
R3341  Q_RES  33.2 1% CHIP  pkg 0402LF  page 241 : A = SMB_HOST_CLK_3V3AUX_SDA ; B = SMB_HOST_CLK_GEN2_3V3AUX_SDA
PC727_P1_4  Q_CAP  22UF 16V 20% X6S  pkg C0805  page 290 : A = SW_P12V_PVCCFA_EHV_FIVRA_CPU1_L ; B = GND

(kicad_pcb
	(version 20260206)
	(generator "pcbnew")
	(generator_version "10.0")
	(general
		(thickness 1.6)
		(legacy_teardrops no)
	)
	(paper "A4")
	(title_block
		(title "03242023_DA0F0TMBIJ0_F0T_Motherboard_J_brd_V01_OCP.brd")
		(comment 1 "Grand Teton / footprints 907-909 of 6105")
	)
	(layers
		(0 "F.Cu" signal "TOP")
		(4 "In1.Cu" signal "GND")
		(6 "In2.Cu" signal "IN1")
		(8 "In3.Cu" signal "GND1")
		(10 "In4.Cu" signal "IN2")
		(12 "In5.Cu" signal "GND2")
		(14 "In6.Cu" signal "IN3")
		(16 "In7.Cu" signal "GND3")
		(18 "In8.Cu" signal "VCC")
		(20 "In9.Cu" signal "VCC1")
		(22 "In10.Cu" signal "GND4")
		(24 "In11.Cu" signal "IN4")
		(26 "In12.Cu" signal "GND5")
		(28 "In13.Cu" signal "IN5")
		(30 "In14.Cu" signal "GND6")
		(32 "In15.Cu" signal "IN6")
		(34 "In16.Cu" signal "GND7")
		(2 "B.Cu" signal "BOTTOM")
		(9 "F.Adhes" user "F.Adhesive")
		(11 "B.Adhes" user "B.Adhesive")
		(13 "F.Paste" user "Package Geometry/Pastemask Top")
		(15 "B.Paste" user "Package Geometry/Pastemask Bottom")
		(5 "F.SilkS" user "Ref Des/Silkscreen Top")
		(7 "B.SilkS" user "Ref Des/Silkscreen Bottom")
		(1 "F.Mask" user "Board Geometry/Soldermask Top")
		(3 "B.Mask" user "Board Geometry/Soldermask Bottom")
		(17 "Dwgs.User" user "User.Drawings")
		(19 "Cmts.User" user "User.Comments")
		(21 "Eco1.User" user "User.Eco1")
		(23 "Eco2.User" user "User.Eco2")
		(25 "Edge.Cuts" user "Board Geometry/Outline")
		(27 "Margin" user)
		(31 "F.CrtYd" user "Package Geometry/Place Bound Top")
		(29 "B.CrtYd" user "Package Geometry/Place Bound Bottom")
		(35 "F.Fab" user "Ref Des/Assembly Top")
		(33 "B.Fab" user "Ref Des/Assembly Bottom")
	)
	(footprint ""
		(layer "F.Cu")
		(at 45.857922 -358.11841)
		(property "Reference" "PC727_P1_4"
			(at 0 0 0)
			(layer "F.SilkS")
			(hide yes)
			(effects
				(font
					(size 1.27 1.27)
				)
			)
		)
		(property "Value" ""
			(at 0 0 0)
			(layer "F.Fab")
			(effects
				(font
					(size 1.27 1.27)
				)
			)
		)
		(duplicate_pad_numbers_are_jumpers no)
		(fp_line
			(start -1.524 -0.762)
			(end 1.524 -0.762)
			(stroke
				(width 0.1524)
				(type default)
			)
			(layer "F.SilkS")
		)
		(fp_line
			(start -1.524 0.762)
			(end -1.524 -0.762)
			(stroke
				(width 0.1524)
				(type default)
			)
			(layer "F.SilkS")
		)
		(fp_line
			(start 1.524 -0.762)
			(end 1.524 0.762)
			(stroke
				(width 0.1524)
				(type default)
			)
			(layer "F.SilkS")
		)
		(fp_line
			(start 1.524 0.762)
			(end -1.524 0.762)
			(stroke
				(width 0.1524)
				(type default)
			)
			(layer "F.SilkS")
		)
		(fp_line
			(start -1.1049 -0.724916)
			(end -1.1049 0.724916)
			(stroke
				(width 0.1)
				(type default)
			)
			(layer "F.Fab")
		)
		(fp_line
			(start -1.1049 0.724916)
			(end 1.1049 0.724916)
			(stroke
				(width 0.1)
				(type default)
			)
			(layer "F.Fab")
		)
		(fp_line
			(start 1.1049 -0.724916)
			(end -1.1049 -0.724916)
			(stroke
				(width 0.1)
				(type default)
			)
			(layer "F.Fab")
		)
		(fp_line
			(start 1.1049 0.724916)
			(end 1.1049 -0.724916)
			(stroke
				(width 0.1)
				(type default)
			)
			(layer "F.Fab")
		)
		(pad "1" smd rect
			(at -0.889 0 180)
			(size 1.016 1.27)
			(layers "F.Cu" "F.Mask" "F.Paste")
			(net "SW_P12V_PVCCFA_EHV_FIVRA_CPU1_L")
		)
		(pad "2" smd rect
			(at 0.889 0 180)
			(size 1.016 1.27)
			(layers "F.Cu" "F.Mask" "F.Paste")
			(net "GND")
		)
	)
	(footprint ""
		(layer "F.Cu")
		(at 365.2012 -411.5562)
		(property "Reference" "R4799"
			(at 0 0 0)
			(layer "F.SilkS")
			(hide yes)
			(effects
				(font
					(size 1.27 1.27)
				)
			)
		)
		(property "Value" ""
			(at 0 0 0)
			(layer "F.Fab")
			(effects
				(font
					(size 1.27 1.27)
				)
			)
		)
		(duplicate_pad_numbers_are_jumpers no)
		(fp_line
			(start -0.7874 -0.4064)
			(end 0.7874 -0.4064)
			(stroke
				(width 0.1524)
				(type default)
			)
			(layer "F.SilkS")
		)
		(fp_line
			(start -0.7874 0.4064)
			(end -0.7874 -0.4064)
			(stroke
				(width 0.1524)
				(type default)
			)
			(layer "F.SilkS")
		)
		(fp_line
			(start 0.7874 -0.4064)
			(end 0.7874 0.4064)
			(stroke
				(width 0.1524)
				(type default)
			)
			(layer "F.SilkS")
		)
		(fp_line
			(start 0.7874 0.4064)
			(end -0.7874 0.4064)
			(stroke
				(width 0.1524)
				(type default)
			)
			(layer "F.SilkS")
		)
		(fp_line
			(start -0.67945 -0.305054)
			(end -0.12065 -0.305054)
			(stroke
				(width 0.1)
				(type default)
			)
			(layer "F.Fab")
		)
		(fp_line
			(start -0.67945 0.3048)
			(end -0.67945 -0.305054)
			(stroke
				(width 0.1)
				(type default)
			)
			(layer "F.Fab")
		)
		(fp_line
			(start -0.12065 -0.305054)
			(end -0.12065 -0.2794)
			(stroke
				(width 0.1)
				(type default)
			)
			(layer "F.Fab")
		)
		(fp_line
			(start -0.12065 -0.2794)
			(end 0.12065 -0.2794)
			(stroke
				(width 0.1)
				(type default)
			)
			(layer "F.Fab")
		)
		(fp_line
			(start -0.12065 0.2794)
			(end -0.12065 0.3048)
			(stroke
				(width 0.1)
				(type default)
			)
			(layer "F.Fab")
		)
		(fp_line
			(start -0.12065 0.3048)
			(end -0.67945 0.3048)
			(stroke
				(width 0.1)
				(type default)
			)
			(layer "F.Fab")
		)
		(fp_line
			(start 0.120396 0.2794)
			(end -0.12065 0.2794)
			(stroke
				(width 0.1)
				(type default)
			)
			(layer "F.Fab")
		)
		(fp_line
			(start 0.120396 0.3048)
			(end 0.120396 0.2794)
			(stroke
				(width 0.1)
				(type default)
			)
			(layer "F.Fab")
		)
		(fp_line
			(start 0.12065 -0.3048)
			(end 0.67945 -0.3048)
			(stroke
				(width 0.1)
				(type default)
			)
			(layer "F.Fab")
		)
		(fp_line
			(start 0.12065 -0.2794)
			(end 0.12065 -0.3048)
			(stroke
				(width 0.1)
				(type default)
			)
			(layer "F.Fab")
		)
		(fp_line
			(start 0.67945 -0.3048)
			(end 0.67945 0.3048)
			(stroke
				(width 0.1)
				(type default)
			)
			(layer "F.Fab")
		)
		(fp_line
			(start 0.67945 0.3048)
			(end 0.120396 0.3048)
			(stroke
				(width 0.1)
				(type default)
			)
			(layer "F.Fab")
		)
		(pad "1" smd circle
			(at -0.40005 0)
			(size 0 0)
			(layers "F.Cu" "F.Mask" "F.Paste")
			(net "PRSNT_CABLE_GPU_A3_N")
		)
		(pad "2" smd circle
			(at 0.40005 0)
			(size 0 0)
			(layers "F.Cu" "F.Mask" "F.Paste")
			(net "GND")
		)
	)
	(footprint ""
		(layer "F.Cu")
		(at 235.51388 -256.123948 -90)
		(property "Reference" "R3341"
			(at 0 0 270)
			(layer "F.SilkS")
			(hide yes)
			(effects
				(font
					(size 1.27 1.27)
				)
			)
		)
		(property "Value" ""
			(at 0 0 270)
			(layer "F.Fab")
			(effects
				(font
					(size 1.27 1.27)
				)
			)
		)
		(duplicate_pad_numbers_are_jumpers no)
		(fp_line
			(start -0.7874 0.4064)
			(end -0.7874 -0.4064)
			(stroke
				(width 0.1524)
				(type default)
			)
			(layer "F.SilkS")
		)
		(fp_line
			(start 0.7874 0.4064)
			(end -0.7874 0.4064)
			(stroke
				(width 0.1524)
				(type default)
			)
			(layer "F.SilkS")
		)
		(fp_line
			(start -0.7874 -0.4064)
			(end 0.7874 -0.4064)
			(stroke
				(width 0.1524)
				(type default)
			)
			(layer "F.SilkS")
		)
		(fp_line
			(start 0.7874 -0.4064)
			(end 0.7874 0.4064)
			(stroke
				(width 0.1524)
				(type default)
			)
			(layer "F.SilkS")
		)
		(fp_line
			(start -0.67945 0.3048)
			(end -0.67945 -0.305054)
			(stroke
				(width 0.1)
				(type default)
			)
			(layer "F.Fab")
		)
		(fp_line
			(start -0.12065 0.3048)
			(end -0.67945 0.3048)
			(stroke
				(width 0.1)
				(type default)
			)
			(layer "F.Fab")
		)
		(fp_line
			(start 0.120396 0.3048)
			(end 0.120396 0.2794)
			(stroke
				(width 0.1)
				(type default)
			)
			(layer "F.Fab")
		)
		(fp_line
			(start 0.67945 0.3048)
			(end 0.120396 0.3048)
			(stroke
				(width 0.1)
				(type default)
			)
			(layer "F.Fab")
		)
		(fp_line
			(start -0.12065 0.2794)
			(end -0.12065 0.3048)
			(stroke
				(width 0.1)
				(type default)
			)
			(layer "F.Fab")
		)
		(fp_line
			(start 0.120396 0.2794)
			(end -0.12065 0.2794)
			(stroke
				(width 0.1)
				(type default)
			)
			(layer "F.Fab")
		)
		(fp_line
			(start -0.12065 -0.2794)
			(end 0.12065 -0.2794)
			(stroke
				(width 0.1)
				(type default)
			)
			(layer "F.Fab")
		)
		(fp_line
			(start 0.12065 -0.2794)
			(end 0.12065 -0.3048)
			(stroke
				(width 0.1)
				(type default)
			)
			(layer "F.Fab")
		)
		(fp_line
			(start 0.12065 -0.3048)
			(end 0.67945 -0.3048)
			(stroke
				(width 0.1)
				(type default)
			)
			(layer "F.Fab")
		)
		(fp_line
			(start 0.67945 -0.3048)
			(end 0.67945 0.3048)
			(stroke
				(width 0.1)
				(type default)
			)
			(layer "F.Fab")
		)
		(fp_line
			(start -0.67945 -0.305054)
			(end -0.12065 -0.305054)
			(stroke
				(width 0.1)
				(type default)
			)
			(layer "F.Fab")
		)
		(fp_line
			(start -0.12065 -0.305054)
			(end -0.12065 -0.2794)
			(stroke
				(width 0.1)
				(type default)
			)
			(layer "F.Fab")
		)
		(pad "1" smd circle
			(at -0.40005 0 270)
			(size 0 0)
			(layers "F.Cu" "F.Mask" "F.Paste")
			(net "SMB_HOST_CLK_3V3AUX_SDA")
		)
		(pad "2" smd circle
			(at 0.40005 0 270)
			(size 0 0)
			(layers "F.Cu" "F.Mask" "F.Paste")
			(net "SMB_HOST_CLK_GEN2_3V3AUX_SDA")
		)
	)
)
